(kicad_pcb
	(version 20260206)
	(generator "pcbnew")
	(generator_version "10.0")
	(general
		(thickness 1.6)
		(legacy_teardrops no)
	)
	(paper "A4")
	(title_block
		(title "04192023_DAF0TMB3IC0_F0TG_MB_C_brd_V02_OCP.brd")
		(comment 1 "Grand Teton / footprints 4026-4031 of 8354")
	)
	(layers
		(0 "F.Cu" signal "TOP")
		(4 "In1.Cu" signal "GND")
		(6 "In2.Cu" signal "IN1")
		(8 "In3.Cu" signal "GND1")
		(10 "In4.Cu" signal "IN2")
		(12 "In5.Cu" signal "GND2")
		(14 "In6.Cu" signal "IN3")
		(16 "In7.Cu" signal "GND3")
		(18 "In8.Cu" signal "VCC")
		(20 "In9.Cu" signal "VCC1")
		(22 "In10.Cu" signal "GND4")
		(24 "In11.Cu" signal "IN4")
		(26 "In12.Cu" signal "GND5")
		(28 "In13.Cu" signal "IN5")
		(30 "In14.Cu" signal "GND6")
		(32 "In15.Cu" signal "IN6")
		(34 "In16.Cu" signal "GND7")
		(2 "B.Cu" signal "BOTTOM")
		(9 "F.Adhes" user "F.Adhesive")
		(11 "B.Adhes" user "B.Adhesive")
		(13 "F.Paste" user "Package Geometry/Pastemask Top")
		(15 "B.Paste" user "Package Geometry/Pastemask Bottom")
		(5 "F.SilkS" user "Ref Des/Silkscreen Top")
		(7 "B.SilkS" user "Ref Des/Silkscreen Bottom")
		(1 "F.Mask" user "Board Geometry/Soldermask Top")
		(3 "B.Mask" user "Board Geometry/Soldermask Bottom")
		(17 "Dwgs.User" user "User.Drawings")
		(19 "Cmts.User" user "User.Comments")
		(21 "Eco1.User" user "User.Eco1")
		(23 "Eco2.User" user "User.Eco2")
		(25 "Edge.Cuts" user "Board Geometry/Outline")
		(27 "Margin" user)
		(31 "F.CrtYd" user "Package Geometry/Place Bound Top")
		(29 "B.CrtYd" user "Package Geometry/Place Bound Bottom")
		(35 "F.Fab" user "Ref Des/Assembly Top")
		(33 "B.Fab" user "Ref Des/Assembly Bottom")
	)
	(footprint ""
		(layer "F.Cu")
		(at 447.792602 -418.96411 -90)
		(property "Reference" "PR6614"
			(at 0 0 270)
			(layer "F.SilkS")
			(hide yes)
			(effects
				(font
					(size 1.27 1.27)
				)
			)
		)
		(property "Value" ""
			(at 0 0 270)
			(layer "F.Fab")
			(effects
				(font
					(size 1.27 1.27)
				)
			)
		)
		(duplicate_pad_numbers_are_jumpers no)
		(fp_line
			(start -0.7874 0.4064)
			(end -0.7874 -0.4064)
			(stroke
				(width 0.1524)
				(type default)
			)
			(layer "F.SilkS")
		)
		(fp_line
			(start 0.7874 0.4064)
			(end -0.7874 0.4064)
			(stroke
				(width 0.1524)
				(type default)
			)
			(layer "F.SilkS")
		)
		(fp_line
			(start -0.7874 -0.4064)
			(end 0.7874 -0.4064)
			(stroke
				(width 0.1524)
				(type default)
			)
			(layer "F.SilkS")
		)
		(fp_line
			(start 0.7874 -0.4064)
			(end 0.7874 0.4064)
			(stroke
				(width 0.1524)
				(type default)
			)
			(layer "F.SilkS")
		)
		(fp_line
			(start -0.67945 0.3048)
			(end -0.67945 -0.305054)
			(stroke
				(width 0.1)
				(type default)
			)
			(layer "F.Fab")
		)
		(fp_line
			(start -0.12065 0.3048)
			(end -0.67945 0.3048)
			(stroke
				(width 0.1)
				(type default)
			)
			(layer "F.Fab")
		)
		(fp_line
			(start 0.120396 0.3048)
			(end 0.120396 0.2794)
			(stroke
				(width 0.1)
				(type default)
			)
			(layer "F.Fab")
		)
		(fp_line
			(start 0.67945 0.3048)
			(end 0.120396 0.3048)
			(stroke
				(width 0.1)
				(type default)
			)
			(layer "F.Fab")
		)
		(fp_line
			(start -0.12065 0.2794)
			(end -0.12065 0.3048)
			(stroke
				(width 0.1)
				(type default)
			)
			(layer "F.Fab")
		)
		(fp_line
			(start 0.120396 0.2794)
			(end -0.12065 0.2794)
			(stroke
				(width 0.1)
				(type default)
			)
			(layer "F.Fab")
		)
		(fp_line
			(start -0.12065 -0.2794)
			(end 0.12065 -0.2794)
			(stroke
				(width 0.1)
				(type default)
			)
			(layer "F.Fab")
		)
		(fp_line
			(start 0.12065 -0.2794)
			(end 0.12065 -0.3048)
			(stroke
				(width 0.1)
				(type default)
			)
			(layer "F.Fab")
		)
		(fp_line
			(start 0.12065 -0.3048)
			(end 0.67945 -0.3048)
			(stroke
				(width 0.1)
				(type default)
			)
			(layer "F.Fab")
		)
		(fp_line
			(start 0.67945 -0.3048)
			(end 0.67945 0.3048)
			(stroke
				(width 0.1)
				(type default)
			)
			(layer "F.Fab")
		)
		(fp_line
			(start -0.67945 -0.305054)
			(end -0.12065 -0.305054)
			(stroke
				(width 0.1)
				(type default)
			)
			(layer "F.Fab")
		)
		(fp_line
			(start -0.12065 -0.305054)
			(end -0.12065 -0.2794)
			(stroke
				(width 0.1)
				(type default)
			)
			(layer "F.Fab")
		)
		(pad "1" smd circle
			(at -0.40005 0 270)
			(size 0 0)
			(layers "F.Cu" "F.Mask" "F.Paste")
			(net "NC_P0V9_RETIMER_CPU0_IMON8")
		)
		(pad "2" smd circle
			(at 0.40005 0 270)
			(size 0 0)
			(layers "F.Cu" "F.Mask" "F.Paste")
			(net "GND")
		)
	)
	(footprint ""
		(layer "F.Cu")
		(at 393.363958 -323.643752 180)
		(property "Reference" "R437"
			(at 0 0 180)
			(layer "F.SilkS")
			(hide yes)
			(effects
				(font
					(size 1.27 1.27)
				)
			)
		)
		(property "Value" ""
			(at 0 0 180)
			(layer "F.Fab")
			(effects
				(font
					(size 1.27 1.27)
				)
			)
		)
		(duplicate_pad_numbers_are_jumpers no)
		(fp_line
			(start 0.7874 0.4064)
			(end -0.7874 0.4064)
			(stroke
				(width 0.1524)
				(type default)
			)
			(layer "F.SilkS")
		)
		(fp_line
			(start 0.7874 -0.4064)
			(end 0.7874 0.4064)
			(stroke
				(width 0.1524)
				(type default)
			)
			(layer "F.SilkS")
		)
		(fp_line
			(start -0.7874 0.4064)
			(end -0.7874 -0.4064)
			(stroke
				(width 0.1524)
				(type default)
			)
			(layer "F.SilkS")
		)
		(fp_line
			(start -0.7874 -0.4064)
			(end 0.7874 -0.4064)
			(stroke
				(width 0.1524)
				(type default)
			)
			(layer "F.SilkS")
		)
		(fp_line
			(start 0.67945 0.3048)
			(end 0.120396 0.3048)
			(stroke
				(width 0.1)
				(type default)
			)
			(layer "F.Fab")
		)
		(fp_line
			(start 0.67945 -0.3048)
			(end 0.67945 0.3048)
			(stroke
				(width 0.1)
				(type default)
			)
			(layer "F.Fab")
		)
		(fp_line
			(start 0.12065 -0.2794)
			(end 0.12065 -0.3048)
			(stroke
				(width 0.1)
				(type default)
			)
			(layer "F.Fab")
		)
		(fp_line
			(start 0.12065 -0.3048)
			(end 0.67945 -0.3048)
			(stroke
				(width 0.1)
				(type default)
			)
			(layer "F.Fab")
		)
		(fp_line
			(start 0.120396 0.3048)
			(end 0.120396 0.2794)
			(stroke
				(width 0.1)
				(type default)
			)
			(layer "F.Fab")
		)
		(fp_line
			(start 0.120396 0.2794)
			(end -0.12065 0.2794)
			(stroke
				(width 0.1)
				(type default)
			)
			(layer "F.Fab")
		)
		(fp_line
			(start -0.12065 0.3048)
			(end -0.67945 0.3048)
			(stroke
				(width 0.1)
				(type default)
			)
			(layer "F.Fab")
		)
		(fp_line
			(start -0.12065 0.2794)
			(end -0.12065 0.3048)
			(stroke
				(width 0.1)
				(type default)
			)
			(layer "F.Fab")
		)
		(fp_line
			(start -0.12065 -0.2794)
			(end 0.12065 -0.2794)
			(stroke
				(width 0.1)
				(type default)
			)
			(layer "F.Fab")
		)
		(fp_line
			(start -0.12065 -0.305054)
			(end -0.12065 -0.2794)
			(stroke
				(width 0.1)
				(type default)
			)
			(layer "F.Fab")
		)
		(fp_line
			(start -0.67945 0.3048)
			(end -0.67945 -0.305054)
			(stroke
				(width 0.1)
				(type default)
			)
			(layer "F.Fab")
		)
		(fp_line
			(start -0.67945 -0.305054)
			(end -0.12065 -0.305054)
			(stroke
				(width 0.1)
				(type default)
			)
			(layer "F.Fab")
		)
		(pad "1" smd circle
			(at -0.40005 0 180)
			(size 0 0)
			(layers "F.Cu" "F.Mask" "F.Paste")
			(net "PVDD18_S5_P0")
		)
		(pad "2" smd circle
			(at 0.40005 0 180)
			(size 0 0)
			(layers "F.Cu" "F.Mask" "F.Paste")
			(net "IRQ_WAKE_N")
		)
	)
	(footprint ""
		(layer "F.Cu")
		(at 215.519 -115.951 90)
		(property "Reference" "R9022"
			(at 0 0 90)
			(layer "F.SilkS")
			(hide yes)
			(effects
				(font
					(size 1.27 1.27)
				)
			)
		)
		(property "Value" ""
			(at 0 0 90)
			(layer "F.Fab")
			(effects
				(font
					(size 1.27 1.27)
				)
			)
		)
		(duplicate_pad_numbers_are_jumpers no)
		(fp_line
			(start 0.7874 -0.4064)
			(end 0.7874 0.4064)
			(stroke
				(width 0.1524)
				(type default)
			)
			(layer "F.SilkS")
		)
		(fp_line
			(start -0.7874 -0.4064)
			(end 0.7874 -0.4064)
			(stroke
				(width 0.1524)
				(type default)
			)
			(layer "F.SilkS")
		)
		(fp_line
			(start 0.7874 0.4064)
			(end -0.7874 0.4064)
			(stroke
				(width 0.1524)
				(type default)
			)
			(layer "F.SilkS")
		)
		(fp_line
			(start -0.7874 0.4064)
			(end -0.7874 -0.4064)
			(stroke
				(width 0.1524)
				(type default)
			)
			(layer "F.SilkS")
		)
		(fp_line
			(start -0.12065 -0.305054)
			(end -0.12065 -0.2794)
			(stroke
				(width 0.1)
				(type default)
			)
			(layer "F.Fab")
		)
		(fp_line
			(start -0.67945 -0.305054)
			(end -0.12065 -0.305054)
			(stroke
				(width 0.1)
				(type default)
			)
			(layer "F.Fab")
		)
		(fp_line
			(start 0.67945 -0.3048)
			(end 0.67945 0.3048)
			(stroke
				(width 0.1)
				(type default)
			)
			(layer "F.Fab")
		)
		(fp_line
			(start 0.12065 -0.3048)
			(end 0.67945 -0.3048)
			(stroke
				(width 0.1)
				(type default)
			)
			(layer "F.Fab")
		)
		(fp_line
			(start 0.12065 -0.2794)
			(end 0.12065 -0.3048)
			(stroke
				(width 0.1)
				(type default)
			)
			(layer "F.Fab")
		)
		(fp_line
			(start -0.12065 -0.2794)
			(end 0.12065 -0.2794)
			(stroke
				(width 0.1)
				(type default)
			)
			(layer "F.Fab")
		)
		(fp_line
			(start 0.120396 0.2794)
			(end -0.12065 0.2794)
			(stroke
				(width 0.1)
				(type default)
			)
			(layer "F.Fab")
		)
		(fp_line
			(start -0.12065 0.2794)
			(end -0.12065 0.3048)
			(stroke
				(width 0.1)
				(type default)
			)
			(layer "F.Fab")
		)
		(fp_line
			(start 0.67945 0.3048)
			(end 0.120396 0.3048)
			(stroke
				(width 0.1)
				(type default)
			)
			(layer "F.Fab")
		)
		(fp_line
			(start 0.120396 0.3048)
			(end 0.120396 0.2794)
			(stroke
				(width 0.1)
				(type default)
			)
			(layer "F.Fab")
		)
		(fp_line
			(start -0.12065 0.3048)
			(end -0.67945 0.3048)
			(stroke
				(width 0.1)
				(type default)
			)
			(layer "F.Fab")
		)
		(fp_line
			(start -0.67945 0.3048)
			(end -0.67945 -0.305054)
			(stroke
				(width 0.1)
				(type default)
			)
			(layer "F.Fab")
		)
		(pad "1" smd circle
			(at -0.40005 0 90)
			(size 0 0)
			(layers "F.Cu" "F.Mask" "F.Paste")
			(net "OCP_V3_1_P3V3_R3_PWRGD")
		)
		(pad "2" smd circle
			(at 0.40005 0 90)
			(size 0 0)
			(layers "F.Cu" "F.Mask" "F.Paste")
			(net "HP_LVC3_OCP_V3_1_PWRGD")
		)
	)
	(footprint ""
		(layer "F.Cu")
		(at 142.729712 -74.609452)
		(property "Reference" "PC6019"
			(at 0 0 0)
			(layer "F.SilkS")
			(hide yes)
			(effects
				(font
					(size 1.27 1.27)
				)
			)
		)
		(property "Value" ""
			(at 0 0 0)
			(layer "F.Fab")
			(effects
				(font
					(size 1.27 1.27)
				)
			)
		)
		(duplicate_pad_numbers_are_jumpers no)
		(fp_line
			(start -0.7874 -0.4064)
			(end 0.7874 -0.4064)
			(stroke
				(width 0.1524)
				(type default)
			)
			(layer "F.SilkS")
		)
		(fp_line
			(start -0.7874 0.4064)
			(end -0.7874 -0.4064)
			(stroke
				(width 0.1524)
				(type default)
			)
			(layer "F.SilkS")
		)
		(fp_line
			(start 0.7874 -0.4064)
			(end 0.7874 0.4064)
			(stroke
				(width 0.1524)
				(type default)
			)
			(layer "F.SilkS")
		)
		(fp_line
			(start 0.7874 0.4064)
			(end -0.7874 0.4064)
			(stroke
				(width 0.1524)
				(type default)
			)
			(layer "F.SilkS")
		)
		(fp_line
			(start -0.67945 -0.305054)
			(end -0.12065 -0.305054)
			(stroke
				(width 0.1)
				(type default)
			)
			(layer "F.Fab")
		)
		(fp_line
			(start -0.67945 0.3048)
			(end -0.67945 -0.305054)
			(stroke
				(width 0.1)
				(type default)
			)
			(layer "F.Fab")
		)
		(fp_line
			(start -0.12065 -0.305054)
			(end -0.12065 -0.2794)
			(stroke
				(width 0.1)
				(type default)
			)
			(layer "F.Fab")
		)
		(fp_line
			(start -0.12065 -0.2794)
			(end 0.12065 -0.2794)
			(stroke
				(width 0.1)
				(type default)
			)
			(layer "F.Fab")
		)
		(fp_line
			(start -0.12065 0.2794)
			(end -0.12065 0.3048)
			(stroke
				(width 0.1)
				(type default)
			)
			(layer "F.Fab")
		)
		(fp_line
			(start -0.12065 0.3048)
			(end -0.67945 0.3048)
			(stroke
				(width 0.1)
				(type default)
			)
			(layer "F.Fab")
		)
		(fp_line
			(start 0.120396 0.2794)
			(end -0.12065 0.2794)
			(stroke
				(width 0.1)
				(type default)
			)
			(layer "F.Fab")
		)
		(fp_line
			(start 0.120396 0.3048)
			(end 0.120396 0.2794)
			(stroke
				(width 0.1)
				(type default)
			)
			(layer "F.Fab")
		)
		(fp_line
			(start 0.12065 -0.3048)
			(end 0.67945 -0.3048)
			(stroke
				(width 0.1)
				(type default)
			)
			(layer "F.Fab")
		)
		(fp_line
			(start 0.12065 -0.2794)
			(end 0.12065 -0.3048)
			(stroke
				(width 0.1)
				(type default)
			)
			(layer "F.Fab")
		)
		(fp_line
			(start 0.67945 -0.3048)
			(end 0.67945 0.3048)
			(stroke
				(width 0.1)
				(type default)
			)
			(layer "F.Fab")
		)
		(fp_line
			(start 0.67945 0.3048)
			(end 0.120396 0.3048)
			(stroke
				(width 0.1)
				(type default)
			)
			(layer "F.Fab")
		)
		(pad "1" smd circle
			(at -0.40005 0)
			(size 0 0)
			(layers "F.Cu" "F.Mask" "F.Paste")
			(net "P1V8_AUX_FB")
		)
		(pad "2" smd circle
			(at 0.40005 0)
			(size 0 0)
			(layers "F.Cu" "F.Mask" "F.Paste")
			(net "P1V8_AUX")
		)
	)
	(footprint ""
		(layer "F.Cu")
		(at 16.764 -73.66)
		(property "Reference" "C8003"
			(at 0 0 0)
			(layer "F.SilkS")
			(hide yes)
			(effects
				(font
					(size 1.27 1.27)
				)
			)
		)
		(property "Value" ""
			(at 0 0 0)
			(layer "F.Fab")
			(effects
				(font
					(size 1.27 1.27)
				)
			)
		)
		(duplicate_pad_numbers_are_jumpers no)
		(fp_line
			(start -0.7874 -0.4064)
			(end 0.7874 -0.4064)
			(stroke
				(width 0.1524)
				(type default)
			)
			(layer "F.SilkS")
		)
		(fp_line
			(start -0.7874 0.4064)
			(end -0.7874 -0.4064)
			(stroke
				(width 0.1524)
				(type default)
			)
			(layer "F.SilkS")
		)
		(fp_line
			(start 0.7874 -0.4064)
			(end 0.7874 0.4064)
			(stroke
				(width 0.1524)
				(type default)
			)
			(layer "F.SilkS")
		)
		(fp_line
			(start 0.7874 0.4064)
			(end -0.7874 0.4064)
			(stroke
				(width 0.1524)
				(type default)
			)
			(layer "F.SilkS")
		)
		(fp_line
			(start -0.67945 -0.305054)
			(end -0.12065 -0.305054)
			(stroke
				(width 0.1)
				(type default)
			)
			(layer "F.Fab")
		)
		(fp_line
			(start -0.67945 0.3048)
			(end -0.67945 -0.305054)
			(stroke
				(width 0.1)
				(type default)
			)
			(layer "F.Fab")
		)
		(fp_line
			(start -0.12065 -0.305054)
			(end -0.12065 -0.2794)
			(stroke
				(width 0.1)
				(type default)
			)
			(layer "F.Fab")
		)
		(fp_line
			(start -0.12065 -0.2794)
			(end 0.12065 -0.2794)
			(stroke
				(width 0.1)
				(type default)
			)
			(layer "F.Fab")
		)
		(fp_line
			(start -0.12065 0.2794)
			(end -0.12065 0.3048)
			(stroke
				(width 0.1)
				(type default)
			)
			(layer "F.Fab")
		)
		(fp_line
			(start -0.12065 0.3048)
			(end -0.67945 0.3048)
			(stroke
				(width 0.1)
				(type default)
			)
			(layer "F.Fab")
		)
		(fp_line
			(start 0.120396 0.2794)
			(end -0.12065 0.2794)
			(stroke
				(width 0.1)
				(type default)
			)
			(layer "F.Fab")
		)
		(fp_line
			(start 0.120396 0.3048)
			(end 0.120396 0.2794)
			(stroke
				(width 0.1)
				(type default)
			)
			(layer "F.Fab")
		)
		(fp_line
			(start 0.12065 -0.3048)
			(end 0.67945 -0.3048)
			(stroke
				(width 0.1)
				(type default)
			)
			(layer "F.Fab")
		)
		(fp_line
			(start 0.12065 -0.2794)
			(end 0.12065 -0.3048)
			(stroke
				(width 0.1)
				(type default)
			)
			(layer "F.Fab")
		)
		(fp_line
			(start 0.67945 -0.3048)
			(end 0.67945 0.3048)
			(stroke
				(width 0.1)
				(type default)
			)
			(layer "F.Fab")
		)
		(fp_line
			(start 0.67945 0.3048)
			(end 0.120396 0.3048)
			(stroke
				(width 0.1)
				(type default)
			)
			(layer "F.Fab")
		)
		(pad "1" smd circle
			(at -0.40005 0)
			(size 0 0)
			(layers "F.Cu" "F.Mask" "F.Paste")
			(net "OCP_V3_2_PRSNT01_R1_N")
		)
		(pad "2" smd circle
			(at 0.40005 0)
			(size 0 0)
			(layers "F.Cu" "F.Mask" "F.Paste")
			(net "GND")
		)
	)
	(footprint ""
		(layer "F.Cu")
		(at 338.859876 -70.098412 90)
		(property "Reference" "D81"
			(at -3.934714 -0.691642 90)
			(unlocked yes)
			(layer "F.SilkS")
			(effects
				(font
					(size 0.7874 0.5842)
					(thickness 0.1524)
				)
				(justify left)
			)
		)
		(property "Value" ""
			(at 0 0 90)
			(layer "F.Fab")
			(effects
				(font
					(size 1.27 1.27)
				)
			)
		)
		(duplicate_pad_numbers_are_jumpers no)
		(fp_line
			(start 1.16078 -0.4826)
			(end 1.16078 0.4826)
			(stroke
				(width 0.1524)
				(type default)
			)
			(layer "F.SilkS")
		)
		(fp_line
			(start 1.03378 -0.4826)
			(end 1.03378 0.4826)
			(stroke
				(width 0.1524)
				(type default)
			)
			(layer "F.SilkS")
		)
		(fp_line
			(start 0.90678 -0.4826)
			(end 0.90678 0.4826)
			(stroke
				(width 0.1524)
				(type default)
			)
			(layer "F.SilkS")
		)
		(fp_line
			(start -0.64008 -0.4826)
			(end 1.16078 -0.4826)
			(stroke
				(width 0.1524)
				(type default)
			)
			(layer "F.SilkS")
		)
		(fp_line
			(start -0.79248 -0.4826)
			(end 1.03378 -0.4826)
			(stroke
				(width 0.1524)
				(type default)
			)
			(layer "F.SilkS")
		)
		(fp_line
			(start -0.89408 -0.4826)
			(end 0.90678 -0.4826)
			(stroke
				(width 0.1524)
				(type default)
			)
			(layer "F.SilkS")
		)
		(fp_line
			(start 1.16078 0.4826)
			(end -0.64008 0.4826)
			(stroke
				(width 0.1524)
				(type default)
			)
			(layer "F.SilkS")
		)
		(fp_line
			(start 1.03378 0.4826)
			(end -0.79248 0.4826)
			(stroke
				(width 0.1524)
				(type default)
			)
			(layer "F.SilkS")
		)
		(fp_line
			(start 0.90678 0.4826)
			(end -0.90678 0.4826)
			(stroke
				(width 0.1524)
				(type default)
			)
			(layer "F.SilkS")
		)
		(fp_line
			(start -0.90678 0.4826)
			(end -0.90678 -0.4699)
			(stroke
				(width 0.1524)
				(type default)
			)
			(layer "F.SilkS")
		)
		(fp_line
			(start 0.499872 -0.249936)
			(end 0.499872 0.249936)
			(stroke
				(width 0.1)
				(type default)
			)
			(layer "F.Fab")
		)
		(fp_line
			(start -0.499872 -0.249936)
			(end 0.499872 -0.249936)
			(stroke
				(width 0.1)
				(type default)
			)
			(layer "F.Fab")
		)
		(fp_line
			(start 0.499872 0.249936)
			(end -0.499872 0.249936)
			(stroke
				(width 0.1)
				(type default)
			)
			(layer "F.Fab")
		)
		(fp_line
			(start -0.499872 0.249936)
			(end -0.499872 -0.249936)
			(stroke
				(width 0.1)
				(type default)
			)
			(layer "F.Fab")
		)
		(pad "A" smd rect
			(at -0.47498 0 90)
			(size 0.6096 0.7112)
			(layers "F.Cu" "F.Mask" "F.Paste")
			(net "LED_PWRGD_PVDDCR_SOC_P1_R")
		)
		(pad "C" smd rect
			(at 0.47498 0 90)
			(size 0.6096 0.7112)
			(layers "F.Cu" "F.Mask" "F.Paste")
			(net "LED_PWRGD_PVDDCR_SOC_P1_D")
		)
	)
)
